FILE_TYPE = CONNECTIVITY;
{Allegro Design Entry HDL 17.2-2016 S081 (4005846) 1/11/2022}
"PAGE_NUMBER" = 105;
0"NC";
1"P3V3_AUX\g";
2"P12V_S3_AUX_CPU1_NVDIMM\g";
3"P12V_S3_AUX_CPU1_NVDIMM\g";
4"P3V3_AUX\g";
5"GND\g";
6"GND\g";
7"GND\g";
8"GND\g";
9"GND\g";
10"M_D_CPU1_SA_DQ<31:0>";
11"M_D_CPU1_SA_CB<7:0>";
12"M_D_CPU1_SB_CB<7:0>";
13"M_D_CPU1_SA_CA<6:0>";
14"M_D_CPU1_SB_CA<6:0>";
15"M_D_CPU1_SB_DQ<31:0>";
16"M_D_CPU1_SB_DQS_DP<9:0>";
17"M_D_CPU1_SA_DQS_DP<9:0>";
18"M_D_CPU1_SB_DQS_DN<9:0>";
19"M_D_CPU1_SA_DQS_DN<9:0>";
20"M_D_CPU1_SB_DQ<4>";
21"I3C_SPD_DDRABCD_CPU1_LVC1_SCL";
22"I3C_SPD_DDRABCD_CPU1_LVC1_SCL_R8";
23"I3C_SPD_DDRABCD_CPU1_LVC1_SDA";
24"PD_CHD_CPU1_DIMM2_SAA";
25"M_D_CPU1_ALERT_N";
26"RST_M_CD_CPU1_FPGA_N";
27"M_D_CPU1_SA_DQS_DN<9>";
28"M_D_CPU1_SA_DQS_DN<8>";
29"M_D_CPU1_SA_DQS_DN<6>";
30"M_D_CPU1_SA_DQS_DN<7>";
31"M_D_CPU1_SA_DQS_DN<4>";
32"M_D_CPU1_SA_DQS_DN<5>";
33"M_D_CPU1_SA_DQS_DN<3>";
34"M_D_CPU1_SA_DQS_DN<1>";
35"M_D_CPU1_SA_DQS_DN<2>";
36"M_D_CPU1_SA_DQS_DN<0>";
37"M_D_CPU1_SB_DQS_DN<8>";
38"M_D_CPU1_SB_DQS_DN<9>";
39"M_D_CPU1_SB_DQS_DN<7>";
40"M_D_CPU1_SB_DQS_DN<6>";
41"M_D_CPU1_SB_DQS_DN<5>";
42"M_D_CPU1_SB_DQS_DN<4>";
43"M_D_CPU1_SB_DQS_DN<3>";
44"M_D_CPU1_SB_DQS_DN<2>";
45"M_D_CPU1_SB_DQS_DN<1>";
46"M_D_CPU1_SB_DQS_DN<0>";
47"M_D_CPU1_SA_DQS_DP<9>";
48"M_D_CPU1_SA_DQS_DP<8>";
49"M_D_CPU1_SA_DQS_DP<7>";
50"M_D_CPU1_SB_DQS_DP<8>";
51"M_D_CPU1_SA_DQS_DP<0>";
52"M_D_CPU1_SB_DQS_DP<9>";
53"M_D_CPU1_SA_DQS_DP<1>";
54"M_D_CPU1_SA_DQS_DP<2>";
55"M_D_CPU1_SA_DQS_DP<3>";
56"M_D_CPU1_SA_DQS_DP<4>";
57"M_D_CPU1_SA_DQS_DP<5>";
58"M_D_CPU1_SA_DQS_DP<6>";
59"M_D_CPU1_SB_DQS_DP<0>";
60"M_D_CPU1_SB_DQS_DP<1>";
61"M_D_CPU1_SB_DQS_DP<3>";
62"M_D_CPU1_SB_DQS_DP<2>";
63"M_D_CPU1_SB_DQS_DP<4>";
64"M_D_CPU1_SB_DQS_DP<5>";
65"M_D_CPU1_SB_DQS_DP<6>";
66"M_D_CPU1_SB_DQS_DP<7>";
67"M_D_CPU1_SB_CB<2>";
68"M_D_CPU1_SB_CB<5>";
69"M_D_CPU1_SA_DQ<20>";
70"M_D_CPU1_SA_DQ<29>";
71"M_D_CPU1_SA_DQ<30>";
72"M_D_CPU1_SA_DQ<15>";
73"M_D_CPU1_SA_DQ<11>";
74"M_D_CPU1_SA_DQ<12>";
75"M_D_CPU1_SA_DQ<1>";
76"M_D_CPU1_SB_DQ<27>";
77"M_D_CPU1_SB_DQ<26>";
78"M_D_CPU1_SB_DQ<25>";
79"M_D_CPU1_SB_DQ<16>";
80"TP_CHD_CPU1_DIMM2_FRU_0";
81"TP_CHD_CPU1_DIMM2_FRU_1";
82"TP_CHD_CPU1_DIMM2_FRU_2";
83"TP_CHD_CPU1_DIMM2_FRU_3";
84"TP_CHD_CPU1_DIMM2_FRU_4";
85"TP_CHD_CPU1_DIMM2_FRU_5";
86"TP_CHD_CPU1_DIMM2_FRU_6";
87"PWRGD_CHD_CPU1_DIMM2";
88"M_D_CPU1_SB_PAR";
89"M_D_CPU1_SA_PAR";
90"M_D_CPU1_SB_RSP<1>";
91"M_D_CPU1_SA_RSP<1>";
92"M_D_CPU1_SB_DQ<0>";
93"M_D_CPU1_SB_DQ<1>";
94"M_D_CPU1_SB_DQ<2>";
95"M_D_CPU1_SB_DQ<3>";
96"M_D_CPU1_SB_DQ<5>";
97"M_D_CPU1_SB_DQ<6>";
98"M_D_CPU1_SB_DQ<7>";
99"M_D_CPU1_SB_DQ<8>";
100"M_D_CPU1_SB_DQ<9>";
101"M_D_CPU1_SB_DQ<10>";
102"M_D_CPU1_SB_DQ<11>";
103"M_D_CPU1_SB_DQ<12>";
104"M_D_CPU1_SB_DQ<13>";
105"M_D_CPU1_SB_DQ<14>";
106"M_D_CPU1_SB_DQ<15>";
107"M_D_CPU1_SB_DQ<17>";
108"M_D_CPU1_SB_DQ<18>";
109"M_D_CPU1_SB_DQ<19>";
110"M_D_CPU1_SB_DQ<20>";
111"M_D_CPU1_SB_DQ<21>";
112"M_D_CPU1_SB_DQ<22>";
113"M_D_CPU1_SB_DQ<23>";
114"M_D_CPU1_SB_DQ<24>";
115"M_D_CPU1_SB_DQ<28>";
116"M_D_CPU1_SB_DQ<29>";
117"M_D_CPU1_SB_DQ<30>";
118"M_D_CPU1_SB_DQ<31>";
119"M_D_CPU1_SA_DQ<0>";
120"M_D_CPU1_SA_DQ<2>";
121"M_D_CPU1_SA_DQ<3>";
122"M_D_CPU1_SA_DQ<4>";
123"M_D_CPU1_SA_DQ<5>";
124"M_D_CPU1_SA_DQ<6>";
125"M_D_CPU1_SA_DQ<7>";
126"M_D_CPU1_SA_DQ<8>";
127"M_D_CPU1_SA_DQ<9>";
128"M_D_CPU1_SA_DQ<10>";
129"M_D_CPU1_SA_DQ<13>";
130"M_D_CPU1_SA_DQ<14>";
131"M_D_CPU1_SA_DQ<16>";
132"M_D_CPU1_SA_DQ<17>";
133"M_D_CPU1_SA_DQ<18>";
134"M_D_CPU1_SA_DQ<19>";
135"M_D_CPU1_SA_DQ<21>";
136"M_D_CPU1_SA_DQ<22>";
137"M_D_CPU1_SA_DQ<23>";
138"M_D_CPU1_SA_DQ<24>";
139"M_D_CPU1_SA_DQ<25>";
140"M_D_CPU1_SA_DQ<26>";
141"M_D_CPU1_SA_DQ<27>";
142"M_D_CPU1_SA_DQ<28>";
143"M_D_CPU1_SB_CS_N<3>";
144"M_D_CPU1_SA_CS_N<3>";
145"M_D_CPU1_SB_CS_N<2>";
146"M_D_CPU1_SA_CS_N<2>";
147"M_D_CPU1_CLK_DP<1>";
148"M_D_CPU1_CLK_DN<1>";
149"M_D_CPU1_SB_CB<0>";
150"M_D_CPU1_SB_CB<1>";
151"M_D_CPU1_SB_CB<3>";
152"M_D_CPU1_SB_CB<4>";
153"M_D_CPU1_SB_CB<6>";
154"M_D_CPU1_SA_CB<0>";
155"M_D_CPU1_SA_CB<2>";
156"M_D_CPU1_SA_CB<3>";
157"M_D_CPU1_SA_CB<5>";
158"M_D_CPU1_SA_CB<6>";
159"M_D_CPU1_SB_CA<6>";
160"M_D_CPU1_SA_CA<6>";
161"M_D_CPU1_SB_CA<5>";
162"M_D_CPU1_SA_CA<5>";
163"M_D_CPU1_SB_CA<4>";
164"M_D_CPU1_SA_CA<4>";
165"M_D_CPU1_SB_CA<3>";
166"M_D_CPU1_SA_CA<3>";
167"M_D_CPU1_SB_CA<2>";
168"M_D_CPU1_SA_CA<2>";
169"M_D_CPU1_SB_CA<1>";
170"M_D_CPU1_SA_CA<1>";
171"M_D_CPU1_SB_CA<0>";
172"M_D_CPU1_SA_CA<0>";
173"M_D_CPU1_SB_CB<7>";
174"M_D_CPU1_SA_CB<1>";
175"M_D_CPU1_SA_CB<4>";
176"M_D_CPU1_SA_CB<7>";
177"M_D_CPU1_SA_DQ<31>";
178"PD_CHD_CPU1_DIMM2_SAA";
%"UNIVERSAL_GND"
"1","(-2625,-100)","0","logical_power","I1";
;
HDL_POWER"GND"
CDS_LIB"logical_power";
"A"5;
%"TAP"
"1","(-1200,3475)","0","standard","I100";
;
CDS_LIB"standard"
BODY_TYPE"PLUMBING"
HDL_TAP"TRUE";
"B \NAC \NWC"10;
"S \NAC"
BN"15"72;
%"TAP"
"1","(-1200,3575)","0","standard","I101";
;
CDS_LIB"standard"
BODY_TYPE"PLUMBING"
HDL_TAP"TRUE";
"B \NAC \NWC"10;
"S \NAC"
BN"17"132;
%"TAP"
"1","(-1200,3625)","0","standard","I102";
;
CDS_LIB"standard"
BODY_TYPE"PLUMBING"
HDL_TAP"TRUE";
"B \NAC \NWC"10;
"S \NAC"
BN"18"133;
%"TAP"
"1","(-1200,3675)","0","standard","I103";
;
CDS_LIB"standard"
BODY_TYPE"PLUMBING"
HDL_TAP"TRUE";
"B \NAC \NWC"10;
"S \NAC"
BN"19"134;
%"TAP"
"1","(-1200,3725)","0","standard","I104";
;
CDS_LIB"standard"
BODY_TYPE"PLUMBING"
HDL_TAP"TRUE";
"B \NAC \NWC"10;
"S \NAC"
BN"20"69;
%"TAP"
"1","(-1200,3775)","0","standard","I105";
;
CDS_LIB"standard"
BODY_TYPE"PLUMBING"
HDL_TAP"TRUE";
"B \NAC \NWC"10;
"S \NAC"
BN"21"135;
%"TAP"
"1","(-1200,3825)","0","standard","I106";
;
CDS_LIB"standard"
BODY_TYPE"PLUMBING"
HDL_TAP"TRUE";
"B \NAC \NWC"10;
"S \NAC"
BN"22"136;
%"TAP"
"1","(-1200,3875)","0","standard","I107";
;
CDS_LIB"standard"
BODY_TYPE"PLUMBING"
HDL_TAP"TRUE";
"B \NAC \NWC"10;
"S \NAC"
BN"23"137;
%"TAP"
"1","(-1200,3975)","0","standard","I108";
;
CDS_LIB"standard"
BODY_TYPE"PLUMBING"
HDL_TAP"TRUE";
"B \NAC \NWC"10;
"S \NAC"
BN"25"139;
%"TAP"
"1","(-1200,3925)","0","standard","I109";
;
CDS_LIB"standard"
BODY_TYPE"PLUMBING"
HDL_TAP"TRUE";
"B \NAC \NWC"10;
"S \NAC"
BN"24"138;
%"TAP"
"1","(-1200,4025)","0","standard","I110";
;
CDS_LIB"standard"
BODY_TYPE"PLUMBING"
HDL_TAP"TRUE";
"B \NAC \NWC"10;
"S \NAC"
BN"26"140;
%"TAP"
"1","(-1200,4075)","0","standard","I111";
;
CDS_LIB"standard"
BODY_TYPE"PLUMBING"
HDL_TAP"TRUE";
"B \NAC \NWC"10;
"S \NAC"
BN"27"141;
%"TAP"
"1","(-1200,4125)","0","standard","I112";
;
CDS_LIB"standard"
BODY_TYPE"PLUMBING"
HDL_TAP"TRUE";
"B \NAC \NWC"10;
"S \NAC"
BN"28"142;
%"TAP"
"1","(-2850,4225)","2","standard","I114";
;
CDS_LIB"standard"
BODY_TYPE"PLUMBING"
HDL_TAP"TRUE";
"B \NAC \NWC"13;
"S \NAC"
BN"5"162;
%"TAP"
"1","(-2850,4175)","2","standard","I115";
;
CDS_LIB"standard"
BODY_TYPE"PLUMBING"
HDL_TAP"TRUE";
"B \NAC \NWC"13;
"S \NAC"
BN"4"164;
%"TAP"
"1","(-2850,4275)","2","standard","I116";
;
CDS_LIB"standard"
BODY_TYPE"PLUMBING"
HDL_TAP"TRUE";
"B \NAC \NWC"13;
"S \NAC"
BN"6"160;
%"TAP"
"1","(-1200,4275)","0","standard","I117";
;
CDS_LIB"standard"
BODY_TYPE"PLUMBING"
HDL_TAP"TRUE";
"B \NAC \NWC"10;
"S \NAC"
BN"31"177;
%"TAP"
"1","(-1200,4225)","0","standard","I118";
;
CDS_LIB"standard"
BODY_TYPE"PLUMBING"
HDL_TAP"TRUE";
"B \NAC \NWC"10;
"S \NAC"
BN"30"71;
%"TAP"
"1","(-1200,4175)","0","standard","I119";
;
CDS_LIB"standard"
BODY_TYPE"PLUMBING"
HDL_TAP"TRUE";
"B \NAC \NWC"10;
"S \NAC"
BN"29"70;
%"VCC_CORE"
"1","(-3675,2150)","0","logical_power","I12";
;
HDL_POWER"P3V3_AUX"
CDS_LIB"logical_power";
"A"4;
%"UNIVERSAL_GND"
"1","(525,25)","0","logical_power","I120";
;
HDL_POWER"GND"
CDS_LIB"logical_power";
"A"6;
%"UNIVERSAL_GND"
"1","(2150,25)","0","logical_power","I121";
;
HDL_POWER"GND"
CDS_LIB"logical_power";
"A"7;
%"VCC_CORE"
"1","(525,725)","0","logical_power","I122";
;
HDL_POWER"P3V3_AUX"
CDS_LIB"logical_power";
"A"1;
%"Q_CAP"
"1","(525,400)","0","pure_quanta","I123";
;
PART_NUMBER"CH5221MEB00"
TOLERANCE"20%"
VOLTAGE"6.3V"
MATERIAL"X6S"
PACK_TYPE"C0402"
VALUE"2.2UF"
$LOCATION"C96"
CDS_LIB"pure_quanta"
$LOCATION"C96"
CDS_LOCATION"C96"
$SEC"1"
CDS_SEC"1";
"B"
$PN"2"6;
"A"
$PN"1"1;
%"Q_CAP"
"1","(1525,400)","0","pure_quanta","I124";
;
PART_NUMBER"CH6103KEA00"
VOLTAGE"16V"
VALUE"10UF"
TOLERANCE"10%"
PACK_TYPE"C0805"
MATERIAL"X6S"
$LOCATION"C97"
CDS_LIB"pure_quanta"
$LOCATION"C97"
CDS_LOCATION"C97"
$SEC"1"
CDS_SEC"1";
"B"
$PN"2"7;
"A"
$PN"1"2;
%"VCC_CORE"
"1","(1525,725)","0","logical_power","I125";
;
HDL_POWER"P12V_S3_AUX_CPU1_NVDIMM"
CDS_LIB"logical_power";
"A"2;
%"TAP"
"1","(1550,2325)","0","standard","I128";
;
CDS_LIB"standard"
BODY_TYPE"PLUMBING"
HDL_TAP"TRUE";
"B \NAC \NWC"16;
"S \NAC"
BN"0"59;
%"TAP"
"1","(1550,2425)","0","standard","I129";
;
CDS_LIB"standard"
BODY_TYPE"PLUMBING"
HDL_TAP"TRUE";
"B \NAC \NWC"16;
"S \NAC"
BN"1"60;
%"TAP"
"1","(1550,2625)","0","standard","I130";
;
CDS_LIB"standard"
BODY_TYPE"PLUMBING"
HDL_TAP"TRUE";
"B \NAC \NWC"16;
"S \NAC"
BN"3"61;
%"TAP"
"1","(1550,2525)","0","standard","I131";
;
CDS_LIB"standard"
BODY_TYPE"PLUMBING"
HDL_TAP"TRUE";
"B \NAC \NWC"16;
"S \NAC"
BN"2"62;
%"TAP"
"1","(1550,2725)","0","standard","I132";
;
CDS_LIB"standard"
BODY_TYPE"PLUMBING"
HDL_TAP"TRUE";
"B \NAC \NWC"16;
"S \NAC"
BN"4"63;
%"TAP"
"1","(1550,2825)","0","standard","I133";
;
CDS_LIB"standard"
BODY_TYPE"PLUMBING"
HDL_TAP"TRUE";
"B \NAC \NWC"16;
"S \NAC"
BN"5"64;
%"TAP"
"1","(1550,2925)","0","standard","I134";
;
CDS_LIB"standard"
BODY_TYPE"PLUMBING"
HDL_TAP"TRUE";
"B \NAC \NWC"16;
"S \NAC"
BN"6"65;
%"TAP"
"1","(1550,3125)","0","standard","I135";
;
CDS_LIB"standard"
BODY_TYPE"PLUMBING"
HDL_TAP"TRUE";
"B \NAC \NWC"16;
"S \NAC"
BN"8"50;
%"TAP"
"1","(1550,3025)","0","standard","I136";
;
CDS_LIB"standard"
BODY_TYPE"PLUMBING"
HDL_TAP"TRUE";
"B \NAC \NWC"16;
"S \NAC"
BN"7"66;
%"TAP"
"1","(1550,3375)","0","standard","I137";
;
CDS_LIB"standard"
BODY_TYPE"PLUMBING"
HDL_TAP"TRUE";
"B \NAC \NWC"17;
"S \NAC"
BN"0"51;
%"TAP"
"1","(1550,3225)","0","standard","I138";
;
CDS_LIB"standard"
BODY_TYPE"PLUMBING"
HDL_TAP"TRUE";
"B \NAC \NWC"16;
"S \NAC"
BN"9"52;
%"TAP"
"1","(1550,3475)","0","standard","I139";
;
CDS_LIB"standard"
BODY_TYPE"PLUMBING"
HDL_TAP"TRUE";
"B \NAC \NWC"17;
"S \NAC"
BN"1"53;
%"TAP"
"1","(-2850,2075)","2","standard","I14";
;
CDS_LIB"standard"
BODY_TYPE"PLUMBING"
HDL_TAP"TRUE";
"B \NAC \NWC"12;
"S \NAC"
BN"0"149;
%"TAP"
"1","(1550,3575)","0","standard","I140";
;
CDS_LIB"standard"
BODY_TYPE"PLUMBING"
HDL_TAP"TRUE";
"B \NAC \NWC"17;
"S \NAC"
BN"2"54;
%"TAP"
"1","(1550,3675)","0","standard","I141";
;
CDS_LIB"standard"
BODY_TYPE"PLUMBING"
HDL_TAP"TRUE";
"B \NAC \NWC"17;
"S \NAC"
BN"3"55;
%"TAP"
"1","(1550,3775)","0","standard","I142";
;
CDS_LIB"standard"
BODY_TYPE"PLUMBING"
HDL_TAP"TRUE";
"B \NAC \NWC"17;
"S \NAC"
BN"4"56;
%"TAP"
"1","(1550,3875)","0","standard","I143";
;
CDS_LIB"standard"
BODY_TYPE"PLUMBING"
HDL_TAP"TRUE";
"B \NAC \NWC"17;
"S \NAC"
BN"5"57;
%"TAP"
"1","(1550,3975)","0","standard","I144";
;
CDS_LIB"standard"
BODY_TYPE"PLUMBING"
HDL_TAP"TRUE";
"B \NAC \NWC"17;
"S \NAC"
BN"6"58;
%"TAP"
"1","(1550,4075)","0","standard","I145";
;
CDS_LIB"standard"
BODY_TYPE"PLUMBING"
HDL_TAP"TRUE";
"B \NAC \NWC"17;
"S \NAC"
BN"7"49;
%"Q_CAP"
"1","(2150,400)","0","pure_quanta","I146";
;
PART_NUMBER"CH6103KEA00"
TOLERANCE"10%"
VOLTAGE"16V"
PACK_TYPE"C0805"
VALUE"10UF"
MATERIAL"X6S"
$LOCATION"C98"
CDS_LIB"pure_quanta"
$LOCATION"C98"
CDS_LOCATION"C98"
$SEC"1"
CDS_SEC"1";
"B"
$PN"2"7;
"A"
$PN"1"2;
%"UNIVERSAL_GND"
"1","(3225,575)","0","logical_power","I147";
;
HDL_POWER"GND"
CDS_LIB"logical_power";
"A"8;
%"TAP"
"1","(1725,2375)","0","standard","I149";
;
CDS_LIB"standard"
BODY_TYPE"PLUMBING"
HDL_TAP"TRUE";
"B \NAC \NWC"18;
"S \NAC"
BN"1"45;
%"TAP"
"1","(1725,2275)","0","standard","I150";
;
CDS_LIB"standard"
BODY_TYPE"PLUMBING"
HDL_TAP"TRUE";
"B \NAC \NWC"18;
"S \NAC"
BN"0"46;
%"TAP"
"1","(1725,2475)","0","standard","I151";
;
CDS_LIB"standard"
BODY_TYPE"PLUMBING"
HDL_TAP"TRUE";
"B \NAC \NWC"18;
"S \NAC"
BN"2"44;
%"TAP"
"1","(1725,2575)","0","standard","I152";
;
CDS_LIB"standard"
BODY_TYPE"PLUMBING"
HDL_TAP"TRUE";
"B \NAC \NWC"18;
"S \NAC"
BN"3"43;
%"TAP"
"1","(1725,2675)","0","standard","I153";
;
CDS_LIB"standard"
BODY_TYPE"PLUMBING"
HDL_TAP"TRUE";
"B \NAC \NWC"18;
"S \NAC"
BN"4"42;
%"TAP"
"1","(1725,2775)","0","standard","I154";
;
CDS_LIB"standard"
BODY_TYPE"PLUMBING"
HDL_TAP"TRUE";
"B \NAC \NWC"18;
"S \NAC"
BN"5"41;
%"TAP"
"1","(1725,2875)","0","standard","I155";
;
CDS_LIB"standard"
BODY_TYPE"PLUMBING"
HDL_TAP"TRUE";
"B \NAC \NWC"18;
"S \NAC"
BN"6"40;
%"TAP"
"1","(1725,2975)","0","standard","I156";
;
CDS_LIB"standard"
BODY_TYPE"PLUMBING"
HDL_TAP"TRUE";
"B \NAC \NWC"18;
"S \NAC"
BN"7"39;
%"TAP"
"1","(1725,3075)","0","standard","I157";
;
CDS_LIB"standard"
BODY_TYPE"PLUMBING"
HDL_TAP"TRUE";
"B \NAC \NWC"18;
"S \NAC"
BN"8"37;
%"TAP"
"1","(1725,3175)","0","standard","I158";
;
CDS_LIB"standard"
BODY_TYPE"PLUMBING"
HDL_TAP"TRUE";
"B \NAC \NWC"18;
"S \NAC"
BN"9"38;
%"TAP"
"1","(1725,3325)","0","standard","I159";
;
CDS_LIB"standard"
BODY_TYPE"PLUMBING"
HDL_TAP"TRUE";
"B \NAC \NWC"19;
"S \NAC"
BN"0"36;
%"TAP"
"1","(1725,3525)","0","standard","I160";
;
CDS_LIB"standard"
BODY_TYPE"PLUMBING"
HDL_TAP"TRUE";
"B \NAC \NWC"19;
"S \NAC"
BN"2"35;
%"TAP"
"1","(1725,3425)","0","standard","I161";
;
CDS_LIB"standard"
BODY_TYPE"PLUMBING"
HDL_TAP"TRUE";
"B \NAC \NWC"19;
"S \NAC"
BN"1"34;
%"TAP"
"1","(1725,3625)","0","standard","I162";
;
CDS_LIB"standard"
BODY_TYPE"PLUMBING"
HDL_TAP"TRUE";
"B \NAC \NWC"19;
"S \NAC"
BN"3"33;
%"TAP"
"1","(1725,3725)","0","standard","I163";
;
CDS_LIB"standard"
BODY_TYPE"PLUMBING"
HDL_TAP"TRUE";
"B \NAC \NWC"19;
"S \NAC"
BN"4"31;
%"TAP"
"1","(1725,3825)","0","standard","I164";
;
CDS_LIB"standard"
BODY_TYPE"PLUMBING"
HDL_TAP"TRUE";
"B \NAC \NWC"19;
"S \NAC"
BN"5"32;
%"TAP"
"1","(1725,4025)","0","standard","I165";
;
CDS_LIB"standard"
BODY_TYPE"PLUMBING"
HDL_TAP"TRUE";
"B \NAC \NWC"19;
"S \NAC"
BN"7"30;
%"TAP"
"1","(1725,3925)","0","standard","I166";
;
CDS_LIB"standard"
BODY_TYPE"PLUMBING"
HDL_TAP"TRUE";
"B \NAC \NWC"19;
"S \NAC"
BN"6"29;
%"TAP"
"1","(1725,4125)","0","standard","I167";
;
CDS_LIB"standard"
BODY_TYPE"PLUMBING"
HDL_TAP"TRUE";
"B \NAC \NWC"19;
"S \NAC"
BN"8"28;
%"TAP"
"1","(1550,4275)","0","standard","I171";
;
CDS_LIB"standard"
BODY_TYPE"PLUMBING"
HDL_TAP"TRUE";
"B \NAC \NWC"17;
"S \NAC"
BN"9"47;
%"TAP"
"1","(1550,4175)","0","standard","I172";
;
CDS_LIB"standard"
BODY_TYPE"PLUMBING"
HDL_TAP"TRUE";
"B \NAC \NWC"17;
"S \NAC"
BN"8"48;
%"TAP"
"1","(1725,4225)","0","standard","I173";
;
CDS_LIB"standard"
BODY_TYPE"PLUMBING"
HDL_TAP"TRUE";
"B \NAC \NWC"19;
"S \NAC"
BN"9"27;
%"VCC_CORE"
"1","(3225,4825)","0","logical_power","I176";
;
HDL_POWER"P12V_S3_AUX_CPU1_NVDIMM"
CDS_LIB"logical_power";
"A"3;
%"UNIVERSAL_GND"
"1","(4925,575)","0","logical_power","I177";
;
HDL_POWER"GND"
CDS_LIB"logical_power";
"A"9;
%"SCONN288_ADR50017P087CC"
"1","(-2025,2550)","0","pure_quanta","I178";
;
PART_NUMBER"DFHST8FS460"
MATERIAL"IO"
VALUE"SCONN288_ADR50017-P087CC"
PART_TYPE"SMLF"
$LOCATION"J24"
NEEDS_NO_SIZE"TRUE"
CDS_LMAN_SYM_OUTLINE"-450,1875,450,-1875"
CDS_LIB"pure_quanta"
CDS_LOCATION"J24"
$SEC"1"
CDS_SEC"1";
"DQ31_A"
$PN"194"177;
"CB7_A"
$PN"205"176;
"CB4_A"
$PN"58"175;
"CB1_A"
$PN"53"174;
"CB7_B"
$PN"236"173;
"ALERT_N \B"
$PN"62"25;
"CA0_A"
$PN"66"172;
"CA0_B"
$PN"76"171;
"CA1_A"
$PN"211"170;
"CA1_B"
$PN"221"169;
"CA2_A"
$PN"68"168;
"CA2_B"
$PN"78"167;
"CA3_A"
$PN"213"166;
"CA3_B"
$PN"223"165;
"CA4_A"
$PN"70"164;
"CA4_B"
$PN"80"163;
"CA5_A"
$PN"215"162;
"CA5_B"
$PN"225"161;
"CA6_A"
$PN"72"160;
"CA6_B"
$PN"82"159;
"CB6_A"
$PN"203"158;
"CB5_A"
$PN"60"157;
"CB3_A"
$PN"198"156;
"CB2_A"
$PN"196"155;
"CB0_A"
$PN"51"154;
"CB6_B"
$PN"234"153;
"CB5_B"
$PN"91"68;
"CB4_B"
$PN"89"152;
"CB3_B"
$PN"243"151;
"CB2_B"
$PN"241"67;
"CB1_B"
$PN"98"150;
"CB0_B"
$PN"96"149;
"CK_C \B"
$PN"218"148;
"CK_T"
$PN"217"147;
"CS0_A_N"
$PN"64"146;
"CS0_B_N"
$PN"84"145;
"CS1_A_N"
$PN"209"144;
"CS1_B_N"
$PN"229"143;
"DQ30_A"
$PN"192"71;
"DQ29_A"
$PN"49"70;
"DQ28_A"
$PN"47"142;
"DQ27_A"
$PN"187"141;
"DQ26_A"
$PN"185"140;
"DQ25_A"
$PN"42"139;
"DQ24_A"
$PN"40"138;
"DQ23_A"
$PN"183"137;
"DQ22_A"
$PN"181"136;
"DQ21_A"
$PN"38"135;
"DQ20_A"
$PN"36"69;
"DQ19_A"
$PN"176"134;
"DQ18_A"
$PN"174"133;
"DQ17_A"
$PN"31"132;
"DQ16_A"
$PN"29"131;
"DQ15_A"
$PN"172"72;
"DQ14_A"
$PN"170"130;
"DQ13_A"
$PN"27"129;
"DQ12_A"
$PN"25"74;
"DQ11_A"
$PN"165"73;
"DQ10_A"
$PN"163"128;
"DQ9_A"
$PN"20"127;
"DQ8_A"
$PN"18"126;
"DQ7_A"
$PN"161"125;
"DQ6_A"
$PN"159"124;
"DQ5_A"
$PN"16"123;
"DQ4_A"
$PN"14"122;
"DQ3_A"
$PN"154"121;
"DQ2_A"
$PN"152"120;
"DQ1_A"
$PN"9"75;
"DQ0_A"
$PN"7"119;
"DQ31_B"
$PN"287"118;
"DQ30_B"
$PN"285"117;
"DQ29_B"
$PN"142"116;
"DQ28_B"
$PN"140"115;
"DQ27_B"
$PN"280"76;
"DQ26_B"
$PN"278"77;
"DQ25_B"
$PN"135"78;
"DQ24_B"
$PN"133"114;
"DQ23_B"
$PN"276"113;
"DQ22_B"
$PN"274"112;
"DQ21_B"
$PN"131"111;
"DQ20_B"
$PN"129"110;
"DQ19_B"
$PN"269"109;
"DQ18_B"
$PN"267"108;
"DQ17_B"
$PN"124"107;
"DQ16_B"
$PN"122"79;
"DQ15_B"
$PN"265"106;
"DQ14_B"
$PN"263"105;
"DQ13_B"
$PN"120"104;
"DQ12_B"
$PN"118"103;
"DQ11_B"
$PN"258"102;
"DQ10_B"
$PN"256"101;
"DQ9_B"
$PN"113"100;
"DQ8_B"
$PN"111"99;
"DQ7_B"
$PN"254"98;
"DQ6_B"
$PN"252"97;
"DQ5_B"
$PN"109"96;
"DQ4_B"
$PN"107"20;
"DQ3_B"
$PN"247"95;
"DQ2_B"
$PN"245"94;
"DQ1_B"
$PN"102"93;
"DQ0_B"
$PN"100"92;
"HSA"
$PN"148"24;
"HSCL"
$PN"4"22;
"HSDA"
$PN"5"23;
"LBD||RSP_A_N"
$PN"86"91;
"LBS||RSP_B_N"
$PN"87"90;
"PAR_A"
$PN"74"89;
"PAR_B"
$PN"227"88;
"PWR_GOOD||FAIL_N"
$PN"147"87;
"RESET_N \B"
$PN"207"26;
"RFU6"
$PN"232"86;
"RFU5"
$PN"231"85;
"RFU4"
$PN"220"84;
"RFU3"
$PN"150"83;
"RFU2"
$PN"149"82;
"RFU1"
$PN"144"81;
"RFU0"
$PN"2"80;
"VIN_MGMT"
$PN"3"4;
%"SCONN288_ADR50017P087CC"
"3","(4075,2650)","0","pure_quanta","I180";
;
PART_NUMBER"DFHST8FS460"
PART_TYPE"SMLF"
MATERIAL"IO"
VALUE"SCONN288_ADR50017-P087CC"
$LOCATION"J24"
NEEDS_NO_SIZE"TRUE"
CDS_LMAN_SYM_OUTLINE"-450,1775,450,-1775"
CDS_LIB"pure_quanta"
CDS_LOCATION"J24"
$SEC"3"
CDS_SEC"3";
"G3"
$PN"G3"9;
"G2"
$PN"G2"9;
"G1"
$PN"G1"9;
"VSS62"
$PN"141"9;
"VSS61"
$PN"139"9;
"VSS60"
$PN"136"9;
"VSS58"
$PN"132"9;
"VSS104"
$PN"240"8;
"VSS102"
$PN"235"8;
"VSS100"
$PN"230"8;
"VIN_BULK2"
$PN"146"3;
"VIN_BULK1"
$PN"145"3;
"VIN_BULK0"
$PN"1"3;
"VSS126"
$PN"288"8;
"VSS125"
$PN"286"8;
"VSS124"
$PN"284"8;
"VSS123"
$PN"281"8;
"VSS122"
$PN"279"8;
"VSS121"
$PN"277"8;
"VSS120"
$PN"275"8;
"VSS119"
$PN"273"8;
"VSS118"
$PN"270"8;
"VSS117"
$PN"268"8;
"VSS116"
$PN"266"8;
"VSS115"
$PN"264"8;
"VSS114"
$PN"262"8;
"VSS113"
$PN"259"8;
"VSS112"
$PN"257"8;
"VSS111"
$PN"255"8;
"VSS110"
$PN"253"8;
"VSS109"
$PN"251"8;
"VSS108"
$PN"248"8;
"VSS107"
$PN"246"8;
"VSS106"
$PN"244"8;
"VSS105"
$PN"242"8;
"VSS103"
$PN"237"8;
"VSS101"
$PN"233"8;
"VSS99"
$PN"228"8;
"VSS98"
$PN"226"8;
"VSS97"
$PN"224"8;
"VSS96"
$PN"222"8;
"VSS95"
$PN"219"8;
"VSS94"
$PN"216"8;
"VSS93"
$PN"214"8;
"VSS92"
$PN"212"8;
"VSS91"
$PN"210"8;
"VSS90"
$PN"208"8;
"VSS89"
$PN"206"8;
"VSS88"
$PN"204"8;
"VSS87"
$PN"202"8;
"VSS86"
$PN"199"8;
"VSS85"
$PN"197"8;
"VSS84"
$PN"195"8;
"VSS83"
$PN"193"8;
"VSS82"
$PN"191"8;
"VSS81"
$PN"188"8;
"VSS80"
$PN"186"8;
"VSS79"
$PN"184"8;
"VSS78"
$PN"182"8;
"VSS77"
$PN"180"8;
"VSS76"
$PN"177"8;
"VSS75"
$PN"175"8;
"VSS74"
$PN"173"8;
"VSS73"
$PN"171"8;
"VSS72"
$PN"169"8;
"VSS71"
$PN"166"8;
"VSS70"
$PN"164"8;
"VSS69"
$PN"162"8;
"VSS68"
$PN"160"8;
"VSS67"
$PN"158"8;
"VSS66"
$PN"155"8;
"VSS65"
$PN"153"8;
"VSS64"
$PN"151"8;
"VSS63"
$PN"143"9;
"VSS59"
$PN"134"9;
"VSS57"
$PN"130"9;
"VSS56"
$PN"128"9;
"VSS55"
$PN"125"9;
"VSS54"
$PN"123"9;
"VSS53"
$PN"121"9;
"VSS52"
$PN"119"9;
"VSS51"
$PN"117"9;
"VSS50"
$PN"114"9;
"VSS49"
$PN"112"9;
"VSS48"
$PN"110"9;
"VSS47"
$PN"108"9;
"VSS46"
$PN"106"9;
"VSS45"
$PN"103"9;
"VSS44"
$PN"101"9;
"VSS43"
$PN"99"9;
"VSS42"
$PN"97"9;
"VSS41"
$PN"95"9;
"VSS40"
$PN"92"9;
"VSS39"
$PN"90"9;
"VSS38"
$PN"88"9;
"VSS37"
$PN"85"9;
"VSS36"
$PN"83"9;
"VSS35"
$PN"81"9;
"VSS34"
$PN"79"9;
"VSS33"
$PN"77"9;
"VSS32"
$PN"75"9;
"VSS31"
$PN"73"9;
"VSS30"
$PN"71"9;
"VSS29"
$PN"69"9;
"VSS28"
$PN"67"9;
"VSS27"
$PN"65"9;
"VSS26"
$PN"63"9;
"VSS25"
$PN"61"9;
"VSS24"
$PN"59"9;
"VSS23"
$PN"57"9;
"VSS22"
$PN"54"9;
"VSS21"
$PN"52"9;
"VSS20"
$PN"50"9;
"VSS19"
$PN"48"9;
"VSS18"
$PN"46"9;
"VSS17"
$PN"43"9;
"VSS16"
$PN"41"9;
"VSS15"
$PN"39"9;
"VSS14"
$PN"37"9;
"VSS13"
$PN"35"9;
"VSS12"
$PN"32"9;
"VSS11"
$PN"30"9;
"VSS10"
$PN"28"9;
"VSS9"
$PN"26"9;
"VSS8"
$PN"24"9;
"VSS7"
$PN"21"9;
"VSS6"
$PN"19"9;
"VSS5"
$PN"17"9;
"VSS4"
$PN"15"9;
"VSS3"
$PN"13"9;
"VSS2"
$PN"10"9;
"VSS1"
$PN"8"9;
"VSS0"
$PN"6"9;
%"SCONN288_ADR50017P087CC"
"2","(650,3275)","0","pure_quanta","I181";
;
PART_NUMBER"DFHST8FS460"
PART_TYPE"SMLF"
MATERIAL"IO"
VALUE"SCONN288_ADR50017-P087CC"
LOCATION"J24"
NEEDS_NO_SIZE"TRUE"
CDS_LMAN_SYM_OUTLINE"-600,1150,600,-1150"
CDS_LIB"pure_quanta"
$SEC"2"
CDS_SEC"2";
"DQS7_A_C||TDQS7_A_C \B"
$PN"178"30;
"DQS6_A_T||TDQS6_A_T"
$PN"168"58;
"DQS8_B_T||TDQS8_B_T"
$PN"283"50;
"DQS8_B_C||TDQS8_B_C \B"
$PN"282"37;
"DQS7_B_T||TDQS7_B_T"
$PN"272"66;
"DQS0_A_C \B"
$PN"12"36;
"DQS0_A_T"
$PN"11"51;
"DQS0_B_C \B"
$PN"105"46;
"DQS0_B_T"
$PN"104"59;
"DQS1_A_C \B"
$PN"23"34;
"DQS1_A_T"
$PN"22"53;
"DQS1_B_C \B"
$PN"116"45;
"DQS1_B_T"
$PN"115"60;
"DQS2_A_C \B"
$PN"34"35;
"DQS2_A_T"
$PN"33"54;
"DQS2_B_C \B"
$PN"127"44;
"DQS2_B_T"
$PN"126"62;
"DQS3_A_C \B"
$PN"45"33;
"DQS3_A_T"
$PN"44"55;
"DQS3_B_C \B"
$PN"138"43;
"DQS3_B_T"
$PN"137"61;
"DQS4_A_C \B"
$PN"56"31;
"DQS4_A_T"
$PN"55"56;
"DQS4_B_C \B"
$PN"238"42;
"DQS4_B_T"
$PN"239"63;
"DQS5_A_C||TDQS5_A_C||DQS5_A_T||TDQS5_A_T \B"
$PN"156"32;
"DQS5_A_T||TDQS5_A_T"
$PN"157"57;
"DQS5_B_C||TDQS5_B_C \B"
$PN"249"41;
"DQS5_B_T||TDQS5_B_T"
$PN"250"64;
"DQS6_A_C||TDQS6_A_C||DQS6_A_T||TDQS6_A_T \B"
$PN"167"29;
"DQS6_B_C||TDQS6_B_C \B"
$PN"260"40;
"DQS6_B_T||TDQS6_B_T"
$PN"261"65;
"DQS7_A_T||TDQS7_A_T"
$PN"179"49;
"DQS7_B_C||TDQS7_B_C \B"
$PN"271"39;
"DQS8_A_C||TDQS8_A_C \B"
$PN"189"28;
"DQS8_A_T||TDQS8_A_T"
$PN"190"48;
"DQS9_A_C||TDQS9_A_C \B"
$PN"200"27;
"DQS9_A_T||TDQS9_A_T"
$PN"201"47;
"DQS9_B_C||TDQS9_B_C \B"
$PN"94"38;
"DQS9_B_T||TDQS9_B_T||DBI4_B_N"
$PN"93"52;
%"Q_RES"
"1","(-3850,1575)","0","pure_quanta","I183";
;
PART_NUMBER"CS04992FB07"
MATERIAL"CHIP"
VALUE"49.9"
$LOCATION"R3898"
CDS_LIB"pure_quanta"
PACK_TYPE"0402LF"
TOLERANCE"1%"
WATTAGE"1/16W"
CDS_LOCATION"R3898"
$SEC"1"
CDS_SEC"1";
"B"
$PN"2"21;
"A"
$PN"1"22;
%"Q_RES"
"2","(-2625,125)","0","pure_quanta","I2";
;
PART_NUMBER"CS41962FB03"
MATERIAL"CHIP"
TOLERANCE"1%"
WATTAGE"1/16W"
PACK_TYPE"0402LF"
VALUE"196K"
$LOCATION"R80"
CDS_LIB"pure_quanta"
$LOCATION"R80"
CDS_LOCATION"R80"
$SEC"1"
CDS_SEC"1";
"A"
$PN"1"178;
"B"
$PN"2"5;
%"TAP"
"1","(-2850,2125)","2","standard","I26";
;
CDS_LIB"standard"
BODY_TYPE"PLUMBING"
HDL_TAP"TRUE";
"B \NAC \NWC"12;
"S \NAC"
BN"1"150;
%"TAP"
"1","(-2850,2175)","2","standard","I27";
;
CDS_LIB"standard"
BODY_TYPE"PLUMBING"
HDL_TAP"TRUE";
"B \NAC \NWC"12;
"S \NAC"
BN"2"67;
%"TAP"
"1","(-2850,2225)","2","standard","I28";
;
CDS_LIB"standard"
BODY_TYPE"PLUMBING"
HDL_TAP"TRUE";
"B \NAC \NWC"12;
"S \NAC"
BN"3"151;
%"TAP"
"1","(-2850,2275)","2","standard","I29";
;
CDS_LIB"standard"
BODY_TYPE"PLUMBING"
HDL_TAP"TRUE";
"B \NAC \NWC"12;
"S \NAC"
BN"4"152;
%"TAP"
"1","(-2850,2325)","2","standard","I30";
;
CDS_LIB"standard"
BODY_TYPE"PLUMBING"
HDL_TAP"TRUE";
"B \NAC \NWC"12;
"S \NAC"
BN"5"68;
%"TAP"
"1","(-2850,2375)","2","standard","I31";
;
CDS_LIB"standard"
BODY_TYPE"PLUMBING"
HDL_TAP"TRUE";
"B \NAC \NWC"12;
"S \NAC"
BN"6"153;
%"TAP"
"1","(-2850,2425)","2","standard","I32";
;
CDS_LIB"standard"
BODY_TYPE"PLUMBING"
HDL_TAP"TRUE";
"B \NAC \NWC"12;
"S \NAC"
BN"7"173;
%"TAP"
"1","(-2850,2575)","2","standard","I33";
;
CDS_LIB"standard"
BODY_TYPE"PLUMBING"
HDL_TAP"TRUE";
"B \NAC \NWC"11;
"S \NAC"
BN"1"174;
%"TAP"
"1","(-2850,2525)","2","standard","I34";
;
CDS_LIB"standard"
BODY_TYPE"PLUMBING"
HDL_TAP"TRUE";
"B \NAC \NWC"11;
"S \NAC"
BN"0"154;
%"TAP"
"1","(-2850,2625)","2","standard","I35";
;
CDS_LIB"standard"
BODY_TYPE"PLUMBING"
HDL_TAP"TRUE";
"B \NAC \NWC"11;
"S \NAC"
BN"2"155;
%"TAP"
"1","(-2850,2675)","2","standard","I36";
;
CDS_LIB"standard"
BODY_TYPE"PLUMBING"
HDL_TAP"TRUE";
"B \NAC \NWC"11;
"S \NAC"
BN"3"156;
%"TAP"
"1","(-2850,2725)","2","standard","I37";
;
CDS_LIB"standard"
BODY_TYPE"PLUMBING"
HDL_TAP"TRUE";
"B \NAC \NWC"11;
"S \NAC"
BN"4"175;
%"TAP"
"1","(-2850,2825)","2","standard","I38";
;
CDS_LIB"standard"
BODY_TYPE"PLUMBING"
HDL_TAP"TRUE";
"B \NAC \NWC"11;
"S \NAC"
BN"6"158;
%"TAP"
"1","(-2850,2775)","2","standard","I39";
;
CDS_LIB"standard"
BODY_TYPE"PLUMBING"
HDL_TAP"TRUE";
"B \NAC \NWC"11;
"S \NAC"
BN"5"157;
%"TAP"
"1","(-2850,2875)","2","standard","I40";
;
CDS_LIB"standard"
BODY_TYPE"PLUMBING"
HDL_TAP"TRUE";
"B \NAC \NWC"11;
"S \NAC"
BN"7"176;
%"TAP"
"1","(-2850,3575)","2","standard","I41";
;
CDS_LIB"standard"
BODY_TYPE"PLUMBING"
HDL_TAP"TRUE";
"B \NAC \NWC"14;
"S \NAC"
BN"0"171;
%"TAP"
"1","(-2850,3625)","2","standard","I42";
;
CDS_LIB"standard"
BODY_TYPE"PLUMBING"
HDL_TAP"TRUE";
"B \NAC \NWC"14;
"S \NAC"
BN"1"169;
%"TAP"
"1","(-2850,3675)","2","standard","I43";
;
CDS_LIB"standard"
BODY_TYPE"PLUMBING"
HDL_TAP"TRUE";
"B \NAC \NWC"14;
"S \NAC"
BN"2"167;
%"TAP"
"1","(-2850,3725)","2","standard","I44";
;
CDS_LIB"standard"
BODY_TYPE"PLUMBING"
HDL_TAP"TRUE";
"B \NAC \NWC"14;
"S \NAC"
BN"3"165;
%"TAP"
"1","(-2850,3775)","2","standard","I45";
;
CDS_LIB"standard"
BODY_TYPE"PLUMBING"
HDL_TAP"TRUE";
"B \NAC \NWC"14;
"S \NAC"
BN"4"163;
%"TAP"
"1","(-2850,3875)","2","standard","I46";
;
CDS_LIB"standard"
BODY_TYPE"PLUMBING"
HDL_TAP"TRUE";
"B \NAC \NWC"14;
"S \NAC"
BN"6"159;
%"TAP"
"1","(-2850,3825)","2","standard","I47";
;
CDS_LIB"standard"
BODY_TYPE"PLUMBING"
HDL_TAP"TRUE";
"B \NAC \NWC"14;
"S \NAC"
BN"5"161;
%"TAP"
"1","(-2850,3975)","2","standard","I48";
;
CDS_LIB"standard"
BODY_TYPE"PLUMBING"
HDL_TAP"TRUE";
"B \NAC \NWC"13;
"S \NAC"
BN"0"172;
%"TAP"
"1","(-2850,4025)","2","standard","I49";
;
CDS_LIB"standard"
BODY_TYPE"PLUMBING"
HDL_TAP"TRUE";
"B \NAC \NWC"13;
"S \NAC"
BN"1"170;
%"TAP"
"1","(-2850,4075)","2","standard","I50";
;
CDS_LIB"standard"
BODY_TYPE"PLUMBING"
HDL_TAP"TRUE";
"B \NAC \NWC"13;
"S \NAC"
BN"2"168;
%"TAP"
"1","(-2850,4125)","2","standard","I51";
;
CDS_LIB"standard"
BODY_TYPE"PLUMBING"
HDL_TAP"TRUE";
"B \NAC \NWC"13;
"S \NAC"
BN"3"166;
%"TAP"
"1","(-1200,1075)","0","standard","I52";
;
CDS_LIB"standard"
BODY_TYPE"PLUMBING"
HDL_TAP"TRUE";
"B \NAC \NWC"15;
"S \NAC"
BN"0"92;
%"TAP"
"1","(-1200,1125)","0","standard","I53";
;
CDS_LIB"standard"
BODY_TYPE"PLUMBING"
HDL_TAP"TRUE";
"B \NAC \NWC"15;
"S \NAC"
BN"1"93;
%"TAP"
"1","(-1200,1225)","0","standard","I54";
;
CDS_LIB"standard"
BODY_TYPE"PLUMBING"
HDL_TAP"TRUE";
"B \NAC \NWC"15;
"S \NAC"
BN"3"95;
%"TAP"
"1","(-1200,1175)","0","standard","I55";
;
CDS_LIB"standard"
BODY_TYPE"PLUMBING"
HDL_TAP"TRUE";
"B \NAC \NWC"15;
"S \NAC"
BN"2"94;
%"TAP"
"1","(-1200,1275)","0","standard","I56";
;
CDS_LIB"standard"
BODY_TYPE"PLUMBING"
HDL_TAP"TRUE";
"B \NAC \NWC"15;
"S \NAC"
BN"4"20;
%"TAP"
"1","(-1200,1325)","0","standard","I57";
;
CDS_LIB"standard"
BODY_TYPE"PLUMBING"
HDL_TAP"TRUE";
"B \NAC \NWC"15;
"S \NAC"
BN"5"96;
%"TAP"
"1","(-1200,1375)","0","standard","I58";
;
CDS_LIB"standard"
BODY_TYPE"PLUMBING"
HDL_TAP"TRUE";
"B \NAC \NWC"15;
"S \NAC"
BN"6"97;
%"TAP"
"1","(-1200,1475)","0","standard","I59";
;
CDS_LIB"standard"
BODY_TYPE"PLUMBING"
HDL_TAP"TRUE";
"B \NAC \NWC"15;
"S \NAC"
BN"8"99;
%"TAP"
"1","(-1200,1425)","0","standard","I60";
;
CDS_LIB"standard"
BODY_TYPE"PLUMBING"
HDL_TAP"TRUE";
"B \NAC \NWC"15;
"S \NAC"
BN"7"98;
%"TAP"
"1","(-1200,1525)","0","standard","I61";
;
CDS_LIB"standard"
BODY_TYPE"PLUMBING"
HDL_TAP"TRUE";
"B \NAC \NWC"15;
"S \NAC"
BN"9"100;
%"TAP"
"1","(-1200,1575)","0","standard","I62";
;
CDS_LIB"standard"
BODY_TYPE"PLUMBING"
HDL_TAP"TRUE";
"B \NAC \NWC"15;
"S \NAC"
BN"10"101;
%"TAP"
"1","(-1200,1625)","0","standard","I63";
;
CDS_LIB"standard"
BODY_TYPE"PLUMBING"
HDL_TAP"TRUE";
"B \NAC \NWC"15;
"S \NAC"
BN"11"102;
%"TAP"
"1","(-1200,1675)","0","standard","I64";
;
CDS_LIB"standard"
BODY_TYPE"PLUMBING"
HDL_TAP"TRUE";
"B \NAC \NWC"15;
"S \NAC"
BN"12"103;
%"TAP"
"1","(-1200,1725)","0","standard","I65";
;
CDS_LIB"standard"
BODY_TYPE"PLUMBING"
HDL_TAP"TRUE";
"B \NAC \NWC"15;
"S \NAC"
BN"13"104;
%"TAP"
"1","(-1200,1775)","0","standard","I66";
;
CDS_LIB"standard"
BODY_TYPE"PLUMBING"
HDL_TAP"TRUE";
"B \NAC \NWC"15;
"S \NAC"
BN"14"105;
%"TAP"
"1","(-1200,1825)","0","standard","I67";
;
CDS_LIB"standard"
BODY_TYPE"PLUMBING"
HDL_TAP"TRUE";
"B \NAC \NWC"15;
"S \NAC"
BN"15"106;
%"TAP"
"1","(-1200,1925)","0","standard","I68";
;
CDS_LIB"standard"
BODY_TYPE"PLUMBING"
HDL_TAP"TRUE";
"B \NAC \NWC"15;
"S \NAC"
BN"17"107;
%"TAP"
"1","(-1200,1875)","0","standard","I69";
;
CDS_LIB"standard"
BODY_TYPE"PLUMBING"
HDL_TAP"TRUE";
"B \NAC \NWC"15;
"S \NAC"
BN"16"79;
%"TAP"
"1","(-1200,1975)","0","standard","I70";
;
CDS_LIB"standard"
BODY_TYPE"PLUMBING"
HDL_TAP"TRUE";
"B \NAC \NWC"15;
"S \NAC"
BN"18"108;
%"TAP"
"1","(-1200,2025)","0","standard","I71";
;
CDS_LIB"standard"
BODY_TYPE"PLUMBING"
HDL_TAP"TRUE";
"B \NAC \NWC"15;
"S \NAC"
BN"19"109;
%"TAP"
"1","(-1200,2075)","0","standard","I72";
;
CDS_LIB"standard"
BODY_TYPE"PLUMBING"
HDL_TAP"TRUE";
"B \NAC \NWC"15;
"S \NAC"
BN"20"110;
%"TAP"
"1","(-1200,2125)","0","standard","I73";
;
CDS_LIB"standard"
BODY_TYPE"PLUMBING"
HDL_TAP"TRUE";
"B \NAC \NWC"15;
"S \NAC"
BN"21"111;
%"TAP"
"1","(-1200,2175)","0","standard","I74";
;
CDS_LIB"standard"
BODY_TYPE"PLUMBING"
HDL_TAP"TRUE";
"B \NAC \NWC"15;
"S \NAC"
BN"22"112;
%"TAP"
"1","(-1200,2225)","0","standard","I75";
;
CDS_LIB"standard"
BODY_TYPE"PLUMBING"
HDL_TAP"TRUE";
"B \NAC \NWC"15;
"S \NAC"
BN"23"113;
%"TAP"
"1","(-1200,2275)","0","standard","I76";
;
CDS_LIB"standard"
BODY_TYPE"PLUMBING"
HDL_TAP"TRUE";
"B \NAC \NWC"15;
"S \NAC"
BN"24"114;
%"TAP"
"1","(-1200,2375)","0","standard","I77";
;
CDS_LIB"standard"
BODY_TYPE"PLUMBING"
HDL_TAP"TRUE";
"B \NAC \NWC"15;
"S \NAC"
BN"26"77;
%"TAP"
"1","(-1200,2325)","0","standard","I78";
;
CDS_LIB"standard"
BODY_TYPE"PLUMBING"
HDL_TAP"TRUE";
"B \NAC \NWC"15;
"S \NAC"
BN"25"78;
%"TAP"
"1","(-1200,2425)","0","standard","I79";
;
CDS_LIB"standard"
BODY_TYPE"PLUMBING"
HDL_TAP"TRUE";
"B \NAC \NWC"15;
"S \NAC"
BN"27"76;
%"TAP"
"1","(-1200,2475)","0","standard","I80";
;
CDS_LIB"standard"
BODY_TYPE"PLUMBING"
HDL_TAP"TRUE";
"B \NAC \NWC"15;
"S \NAC"
BN"28"115;
%"TAP"
"1","(-1200,2525)","0","standard","I81";
;
CDS_LIB"standard"
BODY_TYPE"PLUMBING"
HDL_TAP"TRUE";
"B \NAC \NWC"15;
"S \NAC"
BN"29"116;
%"TAP"
"1","(-1200,2575)","0","standard","I82";
;
CDS_LIB"standard"
BODY_TYPE"PLUMBING"
HDL_TAP"TRUE";
"B \NAC \NWC"15;
"S \NAC"
BN"30"117;
%"TAP"
"1","(-1200,2625)","0","standard","I83";
;
CDS_LIB"standard"
BODY_TYPE"PLUMBING"
HDL_TAP"TRUE";
"B \NAC \NWC"15;
"S \NAC"
BN"31"118;
%"TAP"
"1","(-1200,2725)","0","standard","I84";
;
CDS_LIB"standard"
BODY_TYPE"PLUMBING"
HDL_TAP"TRUE";
"B \NAC \NWC"10;
"S \NAC"
BN"0"119;
%"TAP"
"1","(-1200,2825)","0","standard","I85";
;
CDS_LIB"standard"
BODY_TYPE"PLUMBING"
HDL_TAP"TRUE";
"B \NAC \NWC"10;
"S \NAC"
BN"2"120;
%"TAP"
"1","(-1200,2775)","0","standard","I86";
;
CDS_LIB"standard"
BODY_TYPE"PLUMBING"
HDL_TAP"TRUE";
"B \NAC \NWC"10;
"S \NAC"
BN"1"75;
%"TAP"
"1","(-1200,2875)","0","standard","I87";
;
CDS_LIB"standard"
BODY_TYPE"PLUMBING"
HDL_TAP"TRUE";
"B \NAC \NWC"10;
"S \NAC"
BN"3"121;
%"TAP"
"1","(-1200,2925)","0","standard","I88";
;
CDS_LIB"standard"
BODY_TYPE"PLUMBING"
HDL_TAP"TRUE";
"B \NAC \NWC"10;
"S \NAC"
BN"4"122;
%"TAP"
"1","(-1200,2975)","0","standard","I89";
;
CDS_LIB"standard"
BODY_TYPE"PLUMBING"
HDL_TAP"TRUE";
"B \NAC \NWC"10;
"S \NAC"
BN"5"123;
%"TAP"
"1","(-1200,3075)","0","standard","I90";
;
CDS_LIB"standard"
BODY_TYPE"PLUMBING"
HDL_TAP"TRUE";
"B \NAC \NWC"10;
"S \NAC"
BN"7"125;
%"TAP"
"1","(-1200,3125)","0","standard","I91";
;
CDS_LIB"standard"
BODY_TYPE"PLUMBING"
HDL_TAP"TRUE";
"B \NAC \NWC"10;
"S \NAC"
BN"8"126;
%"TAP"
"1","(-1200,3025)","0","standard","I92";
;
CDS_LIB"standard"
BODY_TYPE"PLUMBING"
HDL_TAP"TRUE";
"B \NAC \NWC"10;
"S \NAC"
BN"6"124;
%"TAP"
"1","(-1200,3175)","0","standard","I93";
;
CDS_LIB"standard"
BODY_TYPE"PLUMBING"
HDL_TAP"TRUE";
"B \NAC \NWC"10;
"S \NAC"
BN"9"127;
%"TAP"
"1","(-1200,3225)","0","standard","I94";
;
CDS_LIB"standard"
BODY_TYPE"PLUMBING"
HDL_TAP"TRUE";
"B \NAC \NWC"10;
"S \NAC"
BN"10"128;
%"TAP"
"1","(-1200,3275)","0","standard","I95";
;
CDS_LIB"standard"
BODY_TYPE"PLUMBING"
HDL_TAP"TRUE";
"B \NAC \NWC"10;
"S \NAC"
BN"11"73;
%"TAP"
"1","(-1200,3325)","0","standard","I96";
;
CDS_LIB"standard"
BODY_TYPE"PLUMBING"
HDL_TAP"TRUE";
"B \NAC \NWC"10;
"S \NAC"
BN"12"74;
%"TAP"
"1","(-1200,3375)","0","standard","I97";
;
CDS_LIB"standard"
BODY_TYPE"PLUMBING"
HDL_TAP"TRUE";
"B \NAC \NWC"10;
"S \NAC"
BN"13"129;
%"TAP"
"1","(-1200,3425)","0","standard","I98";
;
CDS_LIB"standard"
BODY_TYPE"PLUMBING"
HDL_TAP"TRUE";
"B \NAC \NWC"10;
"S \NAC"
BN"14"130;
%"TAP"
"1","(-1200,3525)","0","standard","I99";
;
CDS_LIB"standard"
BODY_TYPE"PLUMBING"
HDL_TAP"TRUE";
"B \NAC \NWC"10;
"S \NAC"
BN"16"131;
END.
